(kicad_pcb
	(version 20260206)
	(generator "pcbnew")
	(generator_version "10.0")
	(general
		(thickness 1.6)
		(legacy_teardrops no)
	)
	(paper "A4")
	(title_block
		(title "panther-plus-userver — 13130-1b_20150205.brd")
		(comment 1 "Honey Badger (Wiwynn) / footprint 1214 of 1509 (DIMM3), pads 58-64 of 210")
	)
	(layers
		(0 "F.Cu" signal "TOP")
		(4 "In1.Cu" signal "L2")
		(6 "In2.Cu" signal "L3")
		(8 "In3.Cu" signal "L4")
		(10 "In4.Cu" signal "L5")
		(12 "In5.Cu" signal "L6")
		(14 "In6.Cu" signal "L7")
		(16 "In7.Cu" signal "L8")
		(18 "In8.Cu" signal "L9")
		(20 "In9.Cu" signal "L10")
		(22 "In10.Cu" signal "L11")
		(2 "B.Cu" signal "BOTTOM")
		(9 "F.Adhes" user "F.Adhesive")
		(11 "B.Adhes" user "B.Adhesive")
		(13 "F.Paste" user "Package Geometry/Pastemask Top")
		(15 "B.Paste" user "Package Geometry/Pastemask Bottom")
		(5 "F.SilkS" user "Ref Des/Silkscreen Top")
		(7 "B.SilkS" user "Ref Des/Silkscreen Bottom")
		(1 "F.Mask" user "Board Geometry/Soldermask Top")
		(3 "B.Mask" user "Board Geometry/Soldermask Bottom")
		(17 "Dwgs.User" user "User.Drawings")
		(19 "Cmts.User" user "User.Comments")
		(21 "Eco1.User" user "User.Eco1")
		(23 "Eco2.User" user "User.Eco2")
		(25 "Edge.Cuts" user "Board Geometry/Outline")
		(27 "Margin" user)
		(31 "F.CrtYd" user "Package Geometry/Place Bound Top")
		(29 "B.CrtYd" user "Package Geometry/Place Bound Bottom")
		(35 "F.Fab" user "Ref Des/Assembly Top")
		(33 "B.Fab" user "Ref Des/Assembly Bottom")
	)
	(footprint ""
		(layer "B.Cu")
		(at 159.999934 -5.790692)
		(property "Reference" "DIMM3"
			(at 0 0 0)
			(layer "B.SilkS")
			(hide yes)
			(effects
				(font
					(size 1.27 1.27)
				)
				(justify mirror)
			)
		)
		(property "Value" "DDR3-204P-142-COLAY-1-GP-U"
			(at 41.312338 -16.676878 0)
			(unlocked yes)
			(layer "B.Fab")
			(hide yes)
			(effects
				(font
					(size 1.016 1.016)
					(thickness 0.1524)
				)
				(justify mirror)
			)
		)
		(property "Device Type" "AS0A626-J8R6-7H-COLAY-1"
			(at 41.312338 -18.200878 0)
			(unlocked yes)
			(layer "B.Fab")
			(hide yes)
			(effects
				(font
					(size 1.016 1.016)
					(thickness 0.1524)
				)
				(justify mirror)
			)
		)
		(duplicate_pad_numbers_are_jumpers no)
		(pad "56" smd custom
			(at -15.150084 4.100068 180)
			(size 0.1143 0.1143)
			(layers "B.Cu" "B.Mask" "B.Paste")
			(net "M_B_DQ29")
			(options
				(clearance outline)
				(anchor circle)
			)
			(primitives
				(gr_poly
					(pts
						(xy 0 -0.9017) (xy -0.03175 -0.89916) (xy -0.0635 -0.889) (xy -0.09144 -0.87376) (xy -0.11684 -0.85344)
						(xy -0.13716 -0.82804) (xy -0.1524 -0.8001) (xy -0.16256 -0.76835) (xy -0.1651 -0.7366) (xy -0.1651 -0.11938)
						(xy -0.17272 -0.11176) (xy -0.19812 -0.0762) (xy -0.2032 -0.06604) (xy -0.20701 -0.05715) (xy -0.21209 -0.04699)
						(xy -0.2159 -0.03683) (xy -0.21844 -0.02667) (xy -0.22225 -0.01524) (xy -0.22352 -0.00508) (xy -0.22606 0.00508)
						(xy -0.22733 0.01651) (xy -0.22733 0.02667) (xy -0.2286 0.0381) (xy -0.22733 0.04953) (xy -0.22733 0.05969)
						(xy -0.22606 0.07112) (xy -0.22352 0.08128) (xy -0.22225 0.09144) (xy -0.21844 0.10287) (xy -0.2159 0.11303)
						(xy -0.21209 0.12319) (xy -0.20701 0.13335) (xy -0.2032 0.14224) (xy -0.19812 0.1524) (xy -0.17272 0.18796)
						(xy -0.1651 0.19558) (xy -0.1651 0.7366) (xy -0.16256 0.76835) (xy -0.1524 0.8001) (xy -0.13716 0.82804)
						(xy -0.11684 0.85344) (xy -0.09144 0.87376) (xy -0.0635 0.889) (xy -0.03175 0.89916) (xy 0 0.9017)
						(xy 0.03175 0.89916) (xy 0.0635 0.889) (xy 0.09144 0.87376) (xy 0.11684 0.85344) (xy 0.13716 0.82804)
						(xy 0.1524 0.8001) (xy 0.16256 0.76835) (xy 0.1651 0.7366) (xy 0.1651 0.19685) (xy 0.17272 0.18923)
						(xy 0.17907 0.18034) (xy 0.18669 0.17145) (xy 0.19177 0.16256) (xy 0.19812 0.15367) (xy 0.20828 0.13335)
						(xy 0.21971 0.10287) (xy 0.22225 0.09271) (xy 0.22479 0.08128) (xy 0.22606 0.07112) (xy 0.2286 0.05969)
						(xy 0.2286 0.01651) (xy 0.22606 0.00508) (xy 0.22479 -0.00508) (xy 0.22225 -0.01651) (xy 0.21971 -0.02667)
						(xy 0.20828 -0.05715) (xy 0.19812 -0.07747) (xy 0.19177 -0.08636) (xy 0.18669 -0.09525) (xy 0.17907 -0.10414)
						(xy 0.17272 -0.11303) (xy 0.1651 -0.12065) (xy 0.1651 -0.7366) (xy 0.16256 -0.76835) (xy 0.1524 -0.8001)
						(xy 0.13716 -0.82804) (xy 0.11684 -0.85344) (xy 0.09144 -0.87376) (xy 0.0635 -0.889) (xy 0.03175 -0.89916)
					)
					(width 0)
					(fill yes)
				)
			)
		)
		(pad "57" smd custom
			(at -14.85011 -4.100068 180)
			(size 0.1143 0.1143)
			(layers "B.Cu" "B.Mask" "B.Paste")
			(net "M_B_DQ25")
			(options
				(clearance outline)
				(anchor circle)
			)
			(primitives
				(gr_poly
					(pts
						(xy 0 -0.9017) (xy -0.03175 -0.89916) (xy -0.0635 -0.889) (xy -0.09144 -0.87376) (xy -0.11684 -0.85344)
						(xy -0.13716 -0.82804) (xy -0.1524 -0.8001) (xy -0.16256 -0.76835) (xy -0.1651 -0.7366) (xy -0.1651 -0.44958)
						(xy -0.17272 -0.44196) (xy -0.19812 -0.4064) (xy -0.2032 -0.39624) (xy -0.20701 -0.38735) (xy -0.21209 -0.37719)
						(xy -0.2159 -0.36703) (xy -0.21844 -0.35687) (xy -0.22225 -0.34544) (xy -0.22352 -0.33528) (xy -0.22606 -0.32512)
						(xy -0.22733 -0.31369) (xy -0.22733 -0.30353) (xy -0.2286 -0.2921) (xy -0.22733 -0.28067) (xy -0.22733 -0.27051)
						(xy -0.22606 -0.25908) (xy -0.22352 -0.24892) (xy -0.22225 -0.23876) (xy -0.21844 -0.22733) (xy -0.2159 -0.21717)
						(xy -0.21209 -0.20701) (xy -0.20701 -0.19685) (xy -0.2032 -0.18796) (xy -0.19812 -0.1778) (xy -0.17272 -0.14224)
						(xy -0.1651 -0.13462) (xy -0.1651 0.7366) (xy -0.16256 0.76835) (xy -0.1524 0.8001) (xy -0.13716 0.82804)
						(xy -0.11684 0.85344) (xy -0.09144 0.87376) (xy -0.0635 0.889) (xy -0.03175 0.89916) (xy 0 0.9017)
						(xy 0.03175 0.89916) (xy 0.0635 0.889) (xy 0.09144 0.87376) (xy 0.11684 0.85344) (xy 0.13716 0.82804)
						(xy 0.1524 0.8001) (xy 0.16256 0.76835) (xy 0.1651 0.7366) (xy 0.1651 -0.13462) (xy 0.17272 -0.14224)
						(xy 0.19812 -0.1778) (xy 0.2032 -0.18796) (xy 0.20701 -0.19685) (xy 0.21209 -0.20701) (xy 0.2159 -0.21717)
						(xy 0.21844 -0.22733) (xy 0.22225 -0.23876) (xy 0.22352 -0.24892) (xy 0.22606 -0.25908) (xy 0.22733 -0.27051)
						(xy 0.22733 -0.28067) (xy 0.2286 -0.2921) (xy 0.22733 -0.30353) (xy 0.22733 -0.31369) (xy 0.22606 -0.32512)
						(xy 0.22352 -0.33528) (xy 0.22225 -0.34544) (xy 0.21844 -0.35687) (xy 0.2159 -0.36703) (xy 0.21209 -0.37719)
						(xy 0.20701 -0.38735) (xy 0.2032 -0.39624) (xy 0.19812 -0.4064) (xy 0.17272 -0.44196) (xy 0.1651 -0.44958)
						(xy 0.1651 -0.7366) (xy 0.16256 -0.76835) (xy 0.1524 -0.8001) (xy 0.13716 -0.82804) (xy 0.11684 -0.85344)
						(xy 0.09144 -0.87376) (xy 0.0635 -0.889) (xy 0.03175 -0.89916)
					)
					(width 0)
					(fill yes)
				)
			)
		)
		(pad "58" smd custom
			(at -14.549882 4.100068 180)
			(size 0.1143 0.1143)
			(layers "B.Cu" "B.Mask" "B.Paste")
			(net "GND")
			(options
				(clearance outline)
				(anchor circle)
			)
			(primitives
				(gr_poly
					(pts
						(xy 0 -0.9017) (xy -0.03175 -0.89916) (xy -0.0635 -0.889) (xy -0.09144 -0.87376) (xy -0.11684 -0.85344)
						(xy -0.13716 -0.82804) (xy -0.1524 -0.8001) (xy -0.16256 -0.76835) (xy -0.1651 -0.7366) (xy -0.1651 0.13462)
						(xy -0.17272 0.14224) (xy -0.19812 0.1778) (xy -0.2032 0.18796) (xy -0.20701 0.19685) (xy -0.21209 0.20701)
						(xy -0.2159 0.21717) (xy -0.21844 0.22733) (xy -0.22225 0.23876) (xy -0.22352 0.24892) (xy -0.22606 0.25908)
						(xy -0.22733 0.27051) (xy -0.22733 0.28067) (xy -0.2286 0.2921) (xy -0.22733 0.30353) (xy -0.22733 0.31369)
						(xy -0.22606 0.32512) (xy -0.22352 0.33528) (xy -0.22225 0.34544) (xy -0.21844 0.35687) (xy -0.2159 0.36703)
						(xy -0.21209 0.37719) (xy -0.20701 0.38735) (xy -0.2032 0.39624) (xy -0.19812 0.4064) (xy -0.17272 0.44196)
						(xy -0.1651 0.44958) (xy -0.1651 0.7366) (xy -0.16256 0.76835) (xy -0.1524 0.8001) (xy -0.13716 0.82804)
						(xy -0.11684 0.85344) (xy -0.09144 0.87376) (xy -0.0635 0.889) (xy -0.03175 0.89916) (xy 0 0.9017)
						(xy 0.03175 0.89916) (xy 0.0635 0.889) (xy 0.09144 0.87376) (xy 0.11684 0.85344) (xy 0.13716 0.82804)
						(xy 0.1524 0.8001) (xy 0.16256 0.76835) (xy 0.1651 0.7366) (xy 0.1651 0.44958) (xy 0.17272 0.44196)
						(xy 0.19812 0.4064) (xy 0.2032 0.39624) (xy 0.20701 0.38735) (xy 0.21209 0.37719) (xy 0.2159 0.36703)
						(xy 0.21844 0.35687) (xy 0.22225 0.34544) (xy 0.22352 0.33528) (xy 0.22606 0.32512) (xy 0.22733 0.31369)
						(xy 0.22733 0.30353) (xy 0.2286 0.2921) (xy 0.22733 0.28067) (xy 0.22733 0.27051) (xy 0.22606 0.25908)
						(xy 0.22352 0.24892) (xy 0.22225 0.23876) (xy 0.21844 0.22733) (xy 0.2159 0.21717) (xy 0.21209 0.20701)
						(xy 0.20701 0.19685) (xy 0.2032 0.18796) (xy 0.19812 0.1778) (xy 0.17272 0.14224) (xy 0.1651 0.13462)
						(xy 0.1651 -0.7366) (xy 0.16256 -0.76835) (xy 0.1524 -0.8001) (xy 0.13716 -0.82804) (xy 0.11684 -0.85344)
						(xy 0.09144 -0.87376) (xy 0.0635 -0.889) (xy 0.03175 -0.89916)
					)
					(width 0)
					(fill yes)
				)
			)
		)
		(pad "59" smd custom
			(at -14.249908 -4.100068 180)
			(size 0.1143 0.1143)
			(layers "B.Cu" "B.Mask" "B.Paste")
			(net "GND")
			(options
				(clearance outline)
				(anchor circle)
			)
			(primitives
				(gr_poly
					(pts
						(xy 0 -0.9017) (xy -0.03175 -0.89916) (xy -0.0635 -0.889) (xy -0.09144 -0.87376) (xy -0.11684 -0.85344)
						(xy -0.13716 -0.82804) (xy -0.1524 -0.8001) (xy -0.16256 -0.76835) (xy -0.1651 -0.7366) (xy -0.1651 -0.19685)
						(xy -0.17272 -0.18923) (xy -0.17907 -0.18034) (xy -0.18669 -0.17145) (xy -0.19177 -0.16256) (xy -0.19812 -0.15367)
						(xy -0.20828 -0.13335) (xy -0.21971 -0.10287) (xy -0.22225 -0.09271) (xy -0.22479 -0.08128) (xy -0.22606 -0.07112)
						(xy -0.2286 -0.05969) (xy -0.2286 -0.01651) (xy -0.22606 -0.00508) (xy -0.22479 0.00508) (xy -0.22225 0.01651)
						(xy -0.21971 0.02667) (xy -0.20828 0.05715) (xy -0.19812 0.07747) (xy -0.19177 0.08636) (xy -0.18669 0.09525)
						(xy -0.17907 0.10414) (xy -0.17272 0.11303) (xy -0.1651 0.12065) (xy -0.1651 0.7366) (xy -0.16256 0.76835)
						(xy -0.1524 0.8001) (xy -0.13716 0.82804) (xy -0.11684 0.85344) (xy -0.09144 0.87376) (xy -0.0635 0.889)
						(xy -0.03175 0.89916) (xy 0 0.9017) (xy 0.03175 0.89916) (xy 0.0635 0.889) (xy 0.09144 0.87376)
						(xy 0.11684 0.85344) (xy 0.13716 0.82804) (xy 0.1524 0.8001) (xy 0.16256 0.76835) (xy 0.1651 0.7366)
						(xy 0.1651 0.11938) (xy 0.17272 0.11176) (xy 0.19812 0.0762) (xy 0.2032 0.06604) (xy 0.20701 0.05715)
						(xy 0.21209 0.04699) (xy 0.2159 0.03683) (xy 0.21844 0.02667) (xy 0.22225 0.01524) (xy 0.22352 0.00508)
						(xy 0.22606 -0.00508) (xy 0.22733 -0.01651) (xy 0.22733 -0.02667) (xy 0.2286 -0.0381) (xy 0.22733 -0.04953)
						(xy 0.22733 -0.05969) (xy 0.22606 -0.07112) (xy 0.22352 -0.08128) (xy 0.22225 -0.09144) (xy 0.21844 -0.10287)
						(xy 0.2159 -0.11303) (xy 0.21209 -0.12319) (xy 0.20701 -0.13335) (xy 0.2032 -0.14224) (xy 0.19812 -0.1524)
						(xy 0.17272 -0.18796) (xy 0.1651 -0.19558) (xy 0.1651 -0.7366) (xy 0.16256 -0.76835) (xy 0.1524 -0.8001)
						(xy 0.13716 -0.82804) (xy 0.11684 -0.85344) (xy 0.09144 -0.87376) (xy 0.0635 -0.889) (xy 0.03175 -0.89916)
					)
					(width 0)
					(fill yes)
				)
			)
		)
		(pad "60" smd custom
			(at -13.949934 4.100068 180)
			(size 0.1143 0.1143)
			(layers "B.Cu" "B.Mask" "B.Paste")
			(net "M_B_DQS_DN3")
			(options
				(clearance outline)
				(anchor circle)
			)
			(primitives
				(gr_poly
					(pts
						(xy 0 -0.9017) (xy -0.03175 -0.89916) (xy -0.0635 -0.889) (xy -0.09144 -0.87376) (xy -0.11684 -0.85344)
						(xy -0.13716 -0.82804) (xy -0.1524 -0.8001) (xy -0.16256 -0.76835) (xy -0.1651 -0.7366) (xy -0.1651 -0.11938)
						(xy -0.17272 -0.11176) (xy -0.19812 -0.0762) (xy -0.2032 -0.06604) (xy -0.20701 -0.05715) (xy -0.21209 -0.04699)
						(xy -0.2159 -0.03683) (xy -0.21844 -0.02667) (xy -0.22225 -0.01524) (xy -0.22352 -0.00508) (xy -0.22606 0.00508)
						(xy -0.22733 0.01651) (xy -0.22733 0.02667) (xy -0.2286 0.0381) (xy -0.22733 0.04953) (xy -0.22733 0.05969)
						(xy -0.22606 0.07112) (xy -0.22352 0.08128) (xy -0.22225 0.09144) (xy -0.21844 0.10287) (xy -0.2159 0.11303)
						(xy -0.21209 0.12319) (xy -0.20701 0.13335) (xy -0.2032 0.14224) (xy -0.19812 0.1524) (xy -0.17272 0.18796)
						(xy -0.1651 0.19558) (xy -0.1651 0.7366) (xy -0.16256 0.76835) (xy -0.1524 0.8001) (xy -0.13716 0.82804)
						(xy -0.11684 0.85344) (xy -0.09144 0.87376) (xy -0.0635 0.889) (xy -0.03175 0.89916) (xy 0 0.9017)
						(xy 0.03175 0.89916) (xy 0.0635 0.889) (xy 0.09144 0.87376) (xy 0.11684 0.85344) (xy 0.13716 0.82804)
						(xy 0.1524 0.8001) (xy 0.16256 0.76835) (xy 0.1651 0.7366) (xy 0.1651 0.19685) (xy 0.17272 0.18923)
						(xy 0.17907 0.18034) (xy 0.18669 0.17145) (xy 0.19177 0.16256) (xy 0.19812 0.15367) (xy 0.20828 0.13335)
						(xy 0.21971 0.10287) (xy 0.22225 0.09271) (xy 0.22479 0.08128) (xy 0.22606 0.07112) (xy 0.2286 0.05969)
						(xy 0.2286 0.01651) (xy 0.22606 0.00508) (xy 0.22479 -0.00508) (xy 0.22225 -0.01651) (xy 0.21971 -0.02667)
						(xy 0.20828 -0.05715) (xy 0.19812 -0.07747) (xy 0.19177 -0.08636) (xy 0.18669 -0.09525) (xy 0.17907 -0.10414)
						(xy 0.17272 -0.11303) (xy 0.1651 -0.12065) (xy 0.1651 -0.7366) (xy 0.16256 -0.76835) (xy 0.1524 -0.8001)
						(xy 0.13716 -0.82804) (xy 0.11684 -0.85344) (xy 0.09144 -0.87376) (xy 0.0635 -0.889) (xy 0.03175 -0.89916)
					)
					(width 0)
					(fill yes)
				)
			)
		)
		(pad "61" smd custom
			(at -13.64996 -4.100068 180)
			(size 0.1143 0.1143)
			(layers "B.Cu" "B.Mask" "B.Paste")
			(net "GND")
			(options
				(clearance outline)
				(anchor circle)
			)
			(primitives
				(gr_poly
					(pts
						(xy 0 -0.9017) (xy -0.03175 -0.89916) (xy -0.0635 -0.889) (xy -0.09144 -0.87376) (xy -0.11684 -0.85344)
						(xy -0.13716 -0.82804) (xy -0.1524 -0.8001) (xy -0.16256 -0.76835) (xy -0.1651 -0.7366) (xy -0.1651 -0.44958)
						(xy -0.17272 -0.44196) (xy -0.19812 -0.4064) (xy -0.2032 -0.39624) (xy -0.20701 -0.38735) (xy -0.21209 -0.37719)
						(xy -0.2159 -0.36703) (xy -0.21844 -0.35687) (xy -0.22225 -0.34544) (xy -0.22352 -0.33528) (xy -0.22606 -0.32512)
						(xy -0.22733 -0.31369) (xy -0.22733 -0.30353) (xy -0.2286 -0.2921) (xy -0.22733 -0.28067) (xy -0.22733 -0.27051)
						(xy -0.22606 -0.25908) (xy -0.22352 -0.24892) (xy -0.22225 -0.23876) (xy -0.21844 -0.22733) (xy -0.2159 -0.21717)
						(xy -0.21209 -0.20701) (xy -0.20701 -0.19685) (xy -0.2032 -0.18796) (xy -0.19812 -0.1778) (xy -0.17272 -0.14224)
						(xy -0.1651 -0.13462) (xy -0.1651 0.7366) (xy -0.16256 0.76835) (xy -0.1524 0.8001) (xy -0.13716 0.82804)
						(xy -0.11684 0.85344) (xy -0.09144 0.87376) (xy -0.0635 0.889) (xy -0.03175 0.89916) (xy 0 0.9017)
						(xy 0.03175 0.89916) (xy 0.0635 0.889) (xy 0.09144 0.87376) (xy 0.11684 0.85344) (xy 0.13716 0.82804)
						(xy 0.1524 0.8001) (xy 0.16256 0.76835) (xy 0.1651 0.7366) (xy 0.1651 -0.13462) (xy 0.17272 -0.14224)
						(xy 0.19812 -0.1778) (xy 0.2032 -0.18796) (xy 0.20701 -0.19685) (xy 0.21209 -0.20701) (xy 0.2159 -0.21717)
						(xy 0.21844 -0.22733) (xy 0.22225 -0.23876) (xy 0.22352 -0.24892) (xy 0.22606 -0.25908) (xy 0.22733 -0.27051)
						(xy 0.22733 -0.28067) (xy 0.2286 -0.2921) (xy 0.22733 -0.30353) (xy 0.22733 -0.31369) (xy 0.22606 -0.32512)
						(xy 0.22352 -0.33528) (xy 0.22225 -0.34544) (xy 0.21844 -0.35687) (xy 0.2159 -0.36703) (xy 0.21209 -0.37719)
						(xy 0.20701 -0.38735) (xy 0.2032 -0.39624) (xy 0.19812 -0.4064) (xy 0.17272 -0.44196) (xy 0.1651 -0.44958)
						(xy 0.1651 -0.7366) (xy 0.16256 -0.76835) (xy 0.1524 -0.8001) (xy 0.13716 -0.82804) (xy 0.11684 -0.85344)
						(xy 0.09144 -0.87376) (xy 0.0635 -0.889) (xy 0.03175 -0.89916)
					)
					(width 0)
					(fill yes)
				)
			)
		)
		(pad "62" smd custom
			(at -13.349986 4.100068 180)
			(size 0.1143 0.1143)
			(layers "B.Cu" "B.Mask" "B.Paste")
			(net "M_B_DQS_DP3")
			(options
				(clearance outline)
				(anchor circle)
			)
			(primitives
				(gr_poly
					(pts
						(xy 0 -0.9017) (xy -0.03175 -0.89916) (xy -0.0635 -0.889) (xy -0.09144 -0.87376) (xy -0.11684 -0.85344)
						(xy -0.13716 -0.82804) (xy -0.1524 -0.8001) (xy -0.16256 -0.76835) (xy -0.1651 -0.7366) (xy -0.1651 0.13462)
						(xy -0.17272 0.14224) (xy -0.19812 0.1778) (xy -0.2032 0.18796) (xy -0.20701 0.19685) (xy -0.21209 0.20701)
						(xy -0.2159 0.21717) (xy -0.21844 0.22733) (xy -0.22225 0.23876) (xy -0.22352 0.24892) (xy -0.22606 0.25908)
						(xy -0.22733 0.27051) (xy -0.22733 0.28067) (xy -0.2286 0.2921) (xy -0.22733 0.30353) (xy -0.22733 0.31369)
						(xy -0.22606 0.32512) (xy -0.22352 0.33528) (xy -0.22225 0.34544) (xy -0.21844 0.35687) (xy -0.2159 0.36703)
						(xy -0.21209 0.37719) (xy -0.20701 0.38735) (xy -0.2032 0.39624) (xy -0.19812 0.4064) (xy -0.17272 0.44196)
						(xy -0.1651 0.44958) (xy -0.1651 0.7366) (xy -0.16256 0.76835) (xy -0.1524 0.8001) (xy -0.13716 0.82804)
						(xy -0.11684 0.85344) (xy -0.09144 0.87376) (xy -0.0635 0.889) (xy -0.03175 0.89916) (xy 0 0.9017)
						(xy 0.03175 0.89916) (xy 0.0635 0.889) (xy 0.09144 0.87376) (xy 0.11684 0.85344) (xy 0.13716 0.82804)
						(xy 0.1524 0.8001) (xy 0.16256 0.76835) (xy 0.1651 0.7366) (xy 0.1651 0.44958) (xy 0.17272 0.44196)
						(xy 0.19812 0.4064) (xy 0.2032 0.39624) (xy 0.20701 0.38735) (xy 0.21209 0.37719) (xy 0.2159 0.36703)
						(xy 0.21844 0.35687) (xy 0.22225 0.34544) (xy 0.22352 0.33528) (xy 0.22606 0.32512) (xy 0.22733 0.31369)
						(xy 0.22733 0.30353) (xy 0.2286 0.2921) (xy 0.22733 0.28067) (xy 0.22733 0.27051) (xy 0.22606 0.25908)
						(xy 0.22352 0.24892) (xy 0.22225 0.23876) (xy 0.21844 0.22733) (xy 0.2159 0.21717) (xy 0.21209 0.20701)
						(xy 0.20701 0.19685) (xy 0.2032 0.18796) (xy 0.19812 0.1778) (xy 0.17272 0.14224) (xy 0.1651 0.13462)
						(xy 0.1651 -0.7366) (xy 0.16256 -0.76835) (xy 0.1524 -0.8001) (xy 0.13716 -0.82804) (xy 0.11684 -0.85344)
						(xy 0.09144 -0.87376) (xy 0.0635 -0.889) (xy 0.03175 -0.89916)
					)
					(width 0)
					(fill yes)
				)
			)
		)
	)
)
